(kicad_pcb
	(version 20260206)
	(generator "pcbnew")
	(generator_version "10.0")
	(general
		(thickness 1.6)
		(legacy_teardrops no)
	)
	(paper "A4")
	(title_block
		(title "v1-chassis-manager — T6M_CM_d_v01_1031_1645.brd")
		(comment 1 "Open CloudServer (Microsoft) / footprints 2284-2293 of 2512")
	)
	(layers
		(0 "F.Cu" signal "TOP")
		(4 "In1.Cu" signal "GND1")
		(6 "In2.Cu" signal "IN1")
		(8 "In3.Cu" signal "VCC1")
		(10 "In4.Cu" signal "VCC2")
		(12 "In5.Cu" signal "GND2")
		(14 "In6.Cu" signal "IN2")
		(16 "In7.Cu" signal "IN3")
		(18 "In8.Cu" signal "GND3")
		(2 "B.Cu" signal "BOTTOM")
		(9 "F.Adhes" user "F.Adhesive")
		(11 "B.Adhes" user "B.Adhesive")
		(13 "F.Paste" user "Package Geometry/Pastemask Top")
		(15 "B.Paste" user "Package Geometry/Pastemask Bottom")
		(5 "F.SilkS" user "Ref Des/Silkscreen Top")
		(7 "B.SilkS" user "Ref Des/Silkscreen Bottom")
		(1 "F.Mask" user "Board Geometry/Soldermask Top")
		(3 "B.Mask" user "Board Geometry/Soldermask Bottom")
		(17 "Dwgs.User" user "User.Drawings")
		(19 "Cmts.User" user "User.Comments")
		(21 "Eco1.User" user "User.Eco1")
		(23 "Eco2.User" user "User.Eco2")
		(25 "Edge.Cuts" user "Board Geometry/Outline")
		(27 "Margin" user)
		(31 "F.CrtYd" user "Package Geometry/Place Bound Top")
		(29 "B.CrtYd" user "Package Geometry/Place Bound Bottom")
		(35 "F.Fab" user "Ref Des/Assembly Top")
		(33 "B.Fab" user "Ref Des/Assembly Bottom")
	)
	(footprint ""
		(layer "B.Cu")
		(at 40.376602 -151.620982)
		(property "Reference" "C428"
			(at -6.359652 -10.149332 0)
			(unlocked yes)
			(layer "B.SilkS")
			(effects
				(font
					(size 0.7874 0.5842)
					(thickness 0.1524)
				)
				(justify left mirror)
			)
		)
		(property "Value" ""
			(at 0 0 0)
			(layer "B.Fab")
			(effects
				(font
					(size 1.27 1.27)
				)
				(justify mirror)
			)
		)
		(duplicate_pad_numbers_are_jumpers no)
		(fp_line
			(start -0.7874 -0.4064)
			(end -0.7874 0.4064)
			(stroke
				(width 0.1524)
				(type default)
			)
			(layer "B.SilkS")
		)
		(fp_line
			(start -0.7874 0.4064)
			(end 0.7874 0.4064)
			(stroke
				(width 0.1524)
				(type default)
			)
			(layer "B.SilkS")
		)
		(fp_line
			(start 0 0.381)
			(end 0 -0.381)
			(stroke
				(width 0.1524)
				(type default)
			)
			(layer "B.SilkS")
		)
		(fp_line
			(start 0.7874 -0.4064)
			(end -0.7874 -0.4064)
			(stroke
				(width 0.1524)
				(type default)
			)
			(layer "B.SilkS")
		)
		(fp_line
			(start 0.7874 0.4064)
			(end 0.7874 -0.4064)
			(stroke
				(width 0.1524)
				(type default)
			)
			(layer "B.SilkS")
		)
		(fp_poly
			(pts
				(xy 0.5334 0.254) (xy 0.635 0.254) (xy 0.635 0.2286) (xy 0.635 -0.254) (xy 0.5334 -0.254) (xy 0.5334 -0.2794)
				(xy -0.5334 -0.2794) (xy -0.5334 -0.254) (xy -0.635 -0.254) (xy -0.635 0.254) (xy -0.5334 0.254)
				(xy -0.5334 0.2794) (xy 0.508 0.2794) (xy 0.5334 0.2794)
			)
			(stroke
				(width 0)
				(type default)
			)
			(fill no)
			(layer "B.CrtYd")
		)
		(pad "1" smd rect
			(at -0.40005 0 180)
			(size 0.4572 0.508)
			(layers "B.Cu" "B.Mask" "B.Paste")
			(net "P1V9_LAN1")
		)
		(pad "2" smd rect
			(at 0.40005 0 180)
			(size 0.4572 0.508)
			(layers "B.Cu" "B.Mask" "B.Paste")
			(net "GND")
		)
	)
	(footprint ""
		(layer "B.Cu")
		(at 115.12169 -164.88537 -90)
		(property "Reference" "R773"
			(at 3.1242 2.45237 270)
			(unlocked yes)
			(layer "B.SilkS")
			(effects
				(font
					(size 0.7874 0.5842)
					(thickness 0.1524)
				)
				(justify left mirror)
			)
		)
		(property "Value" ""
			(at 0 0 90)
			(layer "B.Fab")
			(effects
				(font
					(size 1.27 1.27)
				)
				(justify mirror)
			)
		)
		(duplicate_pad_numbers_are_jumpers no)
		(fp_line
			(start -0.7874 0.4064)
			(end 0.7874 0.4064)
			(stroke
				(width 0.1524)
				(type default)
			)
			(layer "B.SilkS")
		)
		(fp_line
			(start 0.7874 0.4064)
			(end 0.7874 -0.4064)
			(stroke
				(width 0.1524)
				(type default)
			)
			(layer "B.SilkS")
		)
		(fp_line
			(start -0.7874 -0.4064)
			(end -0.7874 0.4064)
			(stroke
				(width 0.1524)
				(type default)
			)
			(layer "B.SilkS")
		)
		(fp_line
			(start 0.7874 -0.4064)
			(end -0.7874 -0.4064)
			(stroke
				(width 0.1524)
				(type default)
			)
			(layer "B.SilkS")
		)
		(fp_poly
			(pts
				(xy 0.508 0.2794) (xy 0.508 0.2286) (xy 0.635 0.2286) (xy 0.635 -0.254) (xy 0.5334 -0.254) (xy 0.5334 -0.2794)
				(xy -0.5334 -0.2794) (xy -0.5334 -0.254) (xy -0.635 -0.254) (xy -0.635 0.254) (xy -0.5334 0.254)
				(xy -0.5334 0.2794)
			)
			(stroke
				(width 0)
				(type default)
			)
			(fill no)
			(layer "B.CrtYd")
		)
		(pad "1" smd rect
			(at -0.40005 0 90)
			(size 0.4572 0.508)
			(layers "B.Cu" "B.Mask" "B.Paste")
			(net "I2C_SCL_FANCTRL2_R")
		)
		(pad "2" smd rect
			(at 0.40005 0 90)
			(size 0.4572 0.508)
			(layers "B.Cu" "B.Mask" "B.Paste")
			(net "I2C_COM3_SCL")
		)
	)
	(footprint ""
		(layer "B.Cu")
		(at 91.102434 -186.826398 180)
		(property "Reference" "R921"
			(at 2.352294 3.135376 0)
			(unlocked yes)
			(layer "B.SilkS")
			(effects
				(font
					(size 0.7874 0.5842)
					(thickness 0.1524)
				)
				(justify left mirror)
			)
		)
		(property "Value" ""
			(at 0 0 0)
			(layer "B.Fab")
			(effects
				(font
					(size 1.27 1.27)
				)
				(justify mirror)
			)
		)
		(duplicate_pad_numbers_are_jumpers no)
		(fp_line
			(start 0.7874 0.4064)
			(end 0.7874 -0.4064)
			(stroke
				(width 0.1524)
				(type default)
			)
			(layer "B.SilkS")
		)
		(fp_line
			(start 0.7874 -0.4064)
			(end -0.7874 -0.4064)
			(stroke
				(width 0.1524)
				(type default)
			)
			(layer "B.SilkS")
		)
		(fp_line
			(start -0.7874 0.4064)
			(end 0.7874 0.4064)
			(stroke
				(width 0.1524)
				(type default)
			)
			(layer "B.SilkS")
		)
		(fp_line
			(start -0.7874 -0.4064)
			(end -0.7874 0.4064)
			(stroke
				(width 0.1524)
				(type default)
			)
			(layer "B.SilkS")
		)
		(fp_poly
			(pts
				(xy 0.508 0.2794) (xy 0.508 0.2286) (xy 0.635 0.2286) (xy 0.635 -0.254) (xy 0.5334 -0.254) (xy 0.5334 -0.2794)
				(xy -0.5334 -0.2794) (xy -0.5334 -0.254) (xy -0.635 -0.254) (xy -0.635 0.254) (xy -0.5334 0.254)
				(xy -0.5334 0.2794)
			)
			(stroke
				(width 0)
				(type default)
			)
			(fill no)
			(layer "B.CrtYd")
		)
		(pad "1" smd rect
			(at -0.40005 0)
			(size 0.4572 0.508)
			(layers "B.Cu" "B.Mask" "B.Paste")
			(net "UART_T5_NODE3_RXD")
		)
		(pad "2" smd rect
			(at 0.40005 0)
			(size 0.4572 0.508)
			(layers "B.Cu" "B.Mask" "B.Paste")
			(net "UART_T5_NODE3_RXD_R")
		)
	)
	(footprint ""
		(layer "B.Cu")
		(at 80.262222 -76.910692)
		(property "Reference" "R91"
			(at 3.545078 0.282194 0)
			(unlocked yes)
			(layer "B.SilkS")
			(effects
				(font
					(size 0.7874 0.5842)
					(thickness 0.1524)
				)
				(justify left mirror)
			)
		)
		(property "Value" ""
			(at 0 0 0)
			(layer "B.Fab")
			(effects
				(font
					(size 1.27 1.27)
				)
				(justify mirror)
			)
		)
		(duplicate_pad_numbers_are_jumpers no)
		(fp_line
			(start -0.7874 -0.4064)
			(end -0.7874 0.4064)
			(stroke
				(width 0.1524)
				(type default)
			)
			(layer "B.SilkS")
		)
		(fp_line
			(start -0.7874 0.4064)
			(end 0.7874 0.4064)
			(stroke
				(width 0.1524)
				(type default)
			)
			(layer "B.SilkS")
		)
		(fp_line
			(start 0.7874 -0.4064)
			(end -0.7874 -0.4064)
			(stroke
				(width 0.1524)
				(type default)
			)
			(layer "B.SilkS")
		)
		(fp_line
			(start 0.7874 0.4064)
			(end 0.7874 -0.4064)
			(stroke
				(width 0.1524)
				(type default)
			)
			(layer "B.SilkS")
		)
		(fp_poly
			(pts
				(xy 0.508 0.2794) (xy 0.508 0.2286) (xy 0.635 0.2286) (xy 0.635 -0.254) (xy 0.5334 -0.254) (xy 0.5334 -0.2794)
				(xy -0.5334 -0.2794) (xy -0.5334 -0.254) (xy -0.635 -0.254) (xy -0.635 0.254) (xy -0.5334 0.254)
				(xy -0.5334 0.2794)
			)
			(stroke
				(width 0)
				(type default)
			)
			(fill no)
			(layer "B.CrtYd")
		)
		(pad "1" smd rect
			(at -0.40005 0 180)
			(size 0.4572 0.508)
			(layers "B.Cu" "B.Mask" "B.Paste")
			(net "H_CPU_NODE1_PROCHOT_R")
		)
		(pad "2" smd rect
			(at 0.40005 0 180)
			(size 0.4572 0.508)
			(layers "B.Cu" "B.Mask" "B.Paste")
			(net "H_CPU_NODE1_PROCHOT_L")
		)
	)
	(footprint ""
		(layer "B.Cu")
		(at 155.05176 -184.951624 90)
		(property "Reference" "R885"
			(at 4.281424 -2.520442 270)
			(unlocked yes)
			(layer "B.SilkS")
			(effects
				(font
					(size 0.7874 0.5842)
					(thickness 0.1524)
				)
				(justify left mirror)
			)
		)
		(property "Value" ""
			(at 0 0 90)
			(layer "B.Fab")
			(effects
				(font
					(size 1.27 1.27)
				)
				(justify mirror)
			)
		)
		(duplicate_pad_numbers_are_jumpers no)
		(fp_line
			(start 0.7874 -0.4064)
			(end -0.7874 -0.4064)
			(stroke
				(width 0.1524)
				(type default)
			)
			(layer "B.SilkS")
		)
		(fp_line
			(start -0.7874 -0.4064)
			(end -0.7874 0.4064)
			(stroke
				(width 0.1524)
				(type default)
			)
			(layer "B.SilkS")
		)
		(fp_line
			(start 0.7874 0.4064)
			(end 0.7874 -0.4064)
			(stroke
				(width 0.1524)
				(type default)
			)
			(layer "B.SilkS")
		)
		(fp_line
			(start -0.7874 0.4064)
			(end 0.7874 0.4064)
			(stroke
				(width 0.1524)
				(type default)
			)
			(layer "B.SilkS")
		)
		(fp_poly
			(pts
				(xy 0.508 0.2794) (xy 0.508 0.2286) (xy 0.635 0.2286) (xy 0.635 -0.254) (xy 0.5334 -0.254) (xy 0.5334 -0.2794)
				(xy -0.5334 -0.2794) (xy -0.5334 -0.254) (xy -0.635 -0.254) (xy -0.635 0.254) (xy -0.5334 0.254)
				(xy -0.5334 0.2794)
			)
			(stroke
				(width 0)
				(type default)
			)
			(fill no)
			(layer "B.CrtYd")
		)
		(pad "1" smd rect
			(at -0.40005 0 270)
			(size 0.4572 0.508)
			(layers "B.Cu" "B.Mask" "B.Paste")
			(net "T11_NODE1_EN")
		)
		(pad "2" smd rect
			(at 0.40005 0 270)
			(size 0.4572 0.508)
			(layers "B.Cu" "B.Mask" "B.Paste")
			(net "T11_NODE1_EN_R")
		)
	)
	(footprint ""
		(layer "B.Cu")
		(at 128.305052 -151.31415 90)
		(property "Reference" "C872"
			(at 2.084578 1.440688 0)
			(unlocked yes)
			(layer "B.SilkS")
			(effects
				(font
					(size 0.7874 0.5842)
					(thickness 0.1524)
				)
				(justify left mirror)
			)
		)
		(property "Value" ""
			(at 0 0 90)
			(layer "B.Fab")
			(effects
				(font
					(size 1.27 1.27)
				)
				(justify mirror)
			)
		)
		(duplicate_pad_numbers_are_jumpers no)
		(fp_line
			(start 0.7874 -0.4064)
			(end -0.7874 -0.4064)
			(stroke
				(width 0.1524)
				(type default)
			)
			(layer "B.SilkS")
		)
		(fp_line
			(start -0.7874 -0.4064)
			(end -0.7874 0.4064)
			(stroke
				(width 0.1524)
				(type default)
			)
			(layer "B.SilkS")
		)
		(fp_line
			(start 0 0.381)
			(end 0 -0.381)
			(stroke
				(width 0.1524)
				(type default)
			)
			(layer "B.SilkS")
		)
		(fp_line
			(start 0.7874 0.4064)
			(end 0.7874 -0.4064)
			(stroke
				(width 0.1524)
				(type default)
			)
			(layer "B.SilkS")
		)
		(fp_line
			(start -0.7874 0.4064)
			(end 0.7874 0.4064)
			(stroke
				(width 0.1524)
				(type default)
			)
			(layer "B.SilkS")
		)
		(fp_poly
			(pts
				(xy 0.5334 0.254) (xy 0.635 0.254) (xy 0.635 0.2286) (xy 0.635 -0.254) (xy 0.5334 -0.254) (xy 0.5334 -0.2794)
				(xy -0.5334 -0.2794) (xy -0.5334 -0.254) (xy -0.635 -0.254) (xy -0.635 0.254) (xy -0.5334 0.254)
				(xy -0.5334 0.2794) (xy 0.508 0.2794) (xy 0.5334 0.2794)
			)
			(stroke
				(width 0)
				(type default)
			)
			(fill no)
			(layer "B.CrtYd")
		)
		(pad "1" smd rect
			(at -0.40005 0 270)
			(size 0.4572 0.508)
			(layers "B.Cu" "B.Mask" "B.Paste")
			(net "P1V0_NODE1")
		)
		(pad "2" smd rect
			(at 0.40005 0 270)
			(size 0.4572 0.508)
			(layers "B.Cu" "B.Mask" "B.Paste")
			(net "GND")
		)
	)
	(footprint ""
		(layer "B.Cu")
		(at 88.77935 -72.161654)
		(property "Reference" "R168"
			(at -1.91516 9.454896 0)
			(unlocked yes)
			(layer "B.SilkS")
			(effects
				(font
					(size 0.7874 0.5842)
					(thickness 0.1524)
				)
				(justify left mirror)
			)
		)
		(property "Value" ""
			(at 0 0 0)
			(layer "B.Fab")
			(effects
				(font
					(size 1.27 1.27)
				)
				(justify mirror)
			)
		)
		(duplicate_pad_numbers_are_jumpers no)
		(fp_line
			(start -0.7874 -0.4064)
			(end -0.7874 0.4064)
			(stroke
				(width 0.1524)
				(type default)
			)
			(layer "B.SilkS")
		)
		(fp_line
			(start -0.7874 0.4064)
			(end 0.7874 0.4064)
			(stroke
				(width 0.1524)
				(type default)
			)
			(layer "B.SilkS")
		)
		(fp_line
			(start 0.7874 -0.4064)
			(end -0.7874 -0.4064)
			(stroke
				(width 0.1524)
				(type default)
			)
			(layer "B.SilkS")
		)
		(fp_line
			(start 0.7874 0.4064)
			(end 0.7874 -0.4064)
			(stroke
				(width 0.1524)
				(type default)
			)
			(layer "B.SilkS")
		)
		(fp_poly
			(pts
				(xy 0.508 0.2794) (xy 0.508 0.2286) (xy 0.635 0.2286) (xy 0.635 -0.254) (xy 0.5334 -0.254) (xy 0.5334 -0.2794)
				(xy -0.5334 -0.2794) (xy -0.5334 -0.254) (xy -0.635 -0.254) (xy -0.635 0.254) (xy -0.5334 0.254)
				(xy -0.5334 0.2794)
			)
			(stroke
				(width 0)
				(type default)
			)
			(fill no)
			(layer "B.CrtYd")
		)
		(pad "1" smd rect
			(at -0.40005 0 180)
			(size 0.4572 0.508)
			(layers "B.Cu" "B.Mask" "B.Paste")
			(net "GND")
		)
		(pad "2" smd rect
			(at 0.40005 0 180)
			(size 0.4572 0.508)
			(layers "B.Cu" "B.Mask" "B.Paste")
			(net "PD_CPU_NODE1_PUNIT_ST_ADDR0")
		)
	)
	(footprint ""
		(layer "B.Cu")
		(at 142.07236 -173.013624 180)
		(property "Reference" "R730"
			(at 1.287272 0.298196 0)
			(unlocked yes)
			(layer "B.SilkS")
			(effects
				(font
					(size 0.7874 0.5842)
					(thickness 0.1524)
				)
				(justify left mirror)
			)
		)
		(property "Value" ""
			(at 0 0 0)
			(layer "B.Fab")
			(effects
				(font
					(size 1.27 1.27)
				)
				(justify mirror)
			)
		)
		(duplicate_pad_numbers_are_jumpers no)
		(fp_line
			(start 0.7874 0.4064)
			(end 0.7874 -0.4064)
			(stroke
				(width 0.1524)
				(type default)
			)
			(layer "B.SilkS")
		)
		(fp_line
			(start 0.7874 -0.4064)
			(end -0.7874 -0.4064)
			(stroke
				(width 0.1524)
				(type default)
			)
			(layer "B.SilkS")
		)
		(fp_line
			(start -0.7874 0.4064)
			(end 0.7874 0.4064)
			(stroke
				(width 0.1524)
				(type default)
			)
			(layer "B.SilkS")
		)
		(fp_line
			(start -0.7874 -0.4064)
			(end -0.7874 0.4064)
			(stroke
				(width 0.1524)
				(type default)
			)
			(layer "B.SilkS")
		)
		(fp_poly
			(pts
				(xy 0.508 0.2794) (xy 0.508 0.2286) (xy 0.635 0.2286) (xy 0.635 -0.254) (xy 0.5334 -0.254) (xy 0.5334 -0.2794)
				(xy -0.5334 -0.2794) (xy -0.5334 -0.254) (xy -0.635 -0.254) (xy -0.635 0.254) (xy -0.5334 0.254)
				(xy -0.5334 0.2794)
			)
			(stroke
				(width 0)
				(type default)
			)
			(fill no)
			(layer "B.CrtYd")
		)
		(pad "1" smd rect
			(at -0.40005 0)
			(size 0.4572 0.508)
			(layers "B.Cu" "B.Mask" "B.Paste")
			(net "T9_NODE3_EN")
		)
		(pad "2" smd rect
			(at 0.40005 0)
			(size 0.4572 0.508)
			(layers "B.Cu" "B.Mask" "B.Paste")
			(net "P5V_NODE1")
		)
	)
	(footprint ""
		(layer "B.Cu")
		(at 50.009298 -82.561938 90)
		(property "Reference" "R102"
			(at -32.484822 -14.724888 270)
			(unlocked yes)
			(layer "B.SilkS")
			(effects
				(font
					(size 0.7874 0.5842)
					(thickness 0.1524)
				)
				(justify left mirror)
			)
		)
		(property "Value" ""
			(at 0 0 90)
			(layer "B.Fab")
			(effects
				(font
					(size 1.27 1.27)
				)
				(justify mirror)
			)
		)
		(duplicate_pad_numbers_are_jumpers no)
		(fp_line
			(start 0.7874 -0.4064)
			(end -0.7874 -0.4064)
			(stroke
				(width 0.1524)
				(type default)
			)
			(layer "B.SilkS")
		)
		(fp_line
			(start -0.7874 -0.4064)
			(end -0.7874 0.4064)
			(stroke
				(width 0.1524)
				(type default)
			)
			(layer "B.SilkS")
		)
		(fp_line
			(start 0.7874 0.4064)
			(end 0.7874 -0.4064)
			(stroke
				(width 0.1524)
				(type default)
			)
			(layer "B.SilkS")
		)
		(fp_line
			(start -0.7874 0.4064)
			(end 0.7874 0.4064)
			(stroke
				(width 0.1524)
				(type default)
			)
			(layer "B.SilkS")
		)
		(fp_poly
			(pts
				(xy 0.508 0.2794) (xy 0.508 0.2286) (xy 0.635 0.2286) (xy 0.635 -0.254) (xy 0.5334 -0.254) (xy 0.5334 -0.2794)
				(xy -0.5334 -0.2794) (xy -0.5334 -0.254) (xy -0.635 -0.254) (xy -0.635 0.254) (xy -0.5334 0.254)
				(xy -0.5334 0.2794)
			)
			(stroke
				(width 0)
				(type default)
			)
			(fill no)
			(layer "B.CrtYd")
		)
		(pad "1" smd rect
			(at -0.40005 0 270)
			(size 0.4572 0.508)
			(layers "B.Cu" "B.Mask" "B.Paste")
			(net "PD_NODE1_NTB_RCOMP")
		)
		(pad "2" smd rect
			(at 0.40005 0 270)
			(size 0.4572 0.508)
			(layers "B.Cu" "B.Mask" "B.Paste")
			(net "GND")
		)
	)
	(footprint ""
		(layer "B.Cu")
		(at 69.96176 -188.126624 -90)
		(property "Reference" "C686"
			(at -4.318254 0.30099 270)
			(unlocked yes)
			(layer "B.SilkS")
			(effects
				(font
					(size 0.7874 0.5842)
					(thickness 0.1524)
				)
				(justify left mirror)
			)
		)
		(property "Value" ""
			(at 0 0 90)
			(layer "B.Fab")
			(effects
				(font
					(size 1.27 1.27)
				)
				(justify mirror)
			)
		)
		(duplicate_pad_numbers_are_jumpers no)
		(fp_line
			(start -0.7874 0.4064)
			(end 0.7874 0.4064)
			(stroke
				(width 0.1524)
				(type default)
			)
			(layer "B.SilkS")
		)
		(fp_line
			(start 0.7874 0.4064)
			(end 0.7874 -0.4064)
			(stroke
				(width 0.1524)
				(type default)
			)
			(layer "B.SilkS")
		)
		(fp_line
			(start 0 0.381)
			(end 0 -0.381)
			(stroke
				(width 0.1524)
				(type default)
			)
			(layer "B.SilkS")
		)
		(fp_line
			(start -0.7874 -0.4064)
			(end -0.7874 0.4064)
			(stroke
				(width 0.1524)
				(type default)
			)
			(layer "B.SilkS")
		)
		(fp_line
			(start 0.7874 -0.4064)
			(end -0.7874 -0.4064)
			(stroke
				(width 0.1524)
				(type default)
			)
			(layer "B.SilkS")
		)
		(fp_poly
			(pts
				(xy 0.5334 0.254) (xy 0.635 0.254) (xy 0.635 0.2286) (xy 0.635 -0.254) (xy 0.5334 -0.254) (xy 0.5334 -0.2794)
				(xy -0.5334 -0.2794) (xy -0.5334 -0.254) (xy -0.635 -0.254) (xy -0.635 0.254) (xy -0.5334 0.254)
				(xy -0.5334 0.2794) (xy 0.508 0.2794) (xy 0.5334 0.2794)
			)
			(stroke
				(width 0)
				(type default)
			)
			(fill no)
			(layer "B.CrtYd")
		)
		(pad "1" smd rect
			(at -0.40005 0 90)
			(size 0.4572 0.508)
			(layers "B.Cu" "B.Mask" "B.Paste")
			(net "UART_T3_NODE3_TXD_R")
		)
		(pad "2" smd rect
			(at 0.40005 0 90)
			(size 0.4572 0.508)
			(layers "B.Cu" "B.Mask" "B.Paste")
			(net "GND")
		)
	)
)
